(kicad_pcb
	(version 20260206)
	(generator "pcbnew")
	(generator_version "10.0")
	(general
		(thickness 1.6)
		(legacy_teardrops no)
	)
	(paper "A4")
	(title_block
		(title "04192023_DAF0TMB3IC0_F0TG_MB_C_brd_V02_OCP.brd")
		(comment 1 "Grand Teton / footprint 2783 of 8354 (U26), pads 4113-4224 of 6102")
	)
	(layers
		(0 "F.Cu" signal "TOP")
		(4 "In1.Cu" signal "GND")
		(6 "In2.Cu" signal "IN1")
		(8 "In3.Cu" signal "GND1")
		(10 "In4.Cu" signal "IN2")
		(12 "In5.Cu" signal "GND2")
		(14 "In6.Cu" signal "IN3")
		(16 "In7.Cu" signal "GND3")
		(18 "In8.Cu" signal "VCC")
		(20 "In9.Cu" signal "VCC1")
		(22 "In10.Cu" signal "GND4")
		(24 "In11.Cu" signal "IN4")
		(26 "In12.Cu" signal "GND5")
		(28 "In13.Cu" signal "IN5")
		(30 "In14.Cu" signal "GND6")
		(32 "In15.Cu" signal "IN6")
		(34 "In16.Cu" signal "GND7")
		(2 "B.Cu" signal "BOTTOM")
		(9 "F.Adhes" user "F.Adhesive")
		(11 "B.Adhes" user "B.Adhesive")
		(13 "F.Paste" user "Package Geometry/Pastemask Top")
		(15 "B.Paste" user "Package Geometry/Pastemask Bottom")
		(5 "F.SilkS" user "Ref Des/Silkscreen Top")
		(7 "B.SilkS" user "Ref Des/Silkscreen Bottom")
		(1 "F.Mask" user "Board Geometry/Soldermask Top")
		(3 "B.Mask" user "Board Geometry/Soldermask Bottom")
		(17 "Dwgs.User" user "User.Drawings")
		(19 "Cmts.User" user "User.Comments")
		(21 "Eco1.User" user "User.Eco1")
		(23 "Eco2.User" user "User.Eco2")
		(25 "Edge.Cuts" user "Board Geometry/Outline")
		(27 "Margin" user)
		(31 "F.CrtYd" user "Package Geometry/Place Bound Top")
		(29 "B.CrtYd" user "Package Geometry/Place Bound Bottom")
		(35 "F.Fab" user "Ref Des/Assembly Top")
		(33 "B.Fab" user "Ref Des/Assembly Bottom")
	)
	(footprint ""
		(layer "F.Cu")
		(at 111.927894 -258.880356 180)
		(property "Reference" "U26"
			(at -45.05579 -61.794136 0)
			(unlocked yes)
			(layer "F.SilkS")
			(effects
				(font
					(size 0.7874 0.5842)
					(thickness 0.1524)
				)
			)
		)
		(property "Value" ""
			(at 0 0 180)
			(layer "F.Fab")
			(effects
				(font
					(size 1.27 1.27)
				)
			)
		)
		(duplicate_pad_numbers_are_jumpers no)
		(pad "CW9" smd circle
			(at -26.940002 28.710128 180)
			(size 0.450088 0.450088)
			(layers "F.Cu" "F.Mask" "F.Paste")
			(net "M_L_CPU1_SB_DQ<22>")
		)
		(pad "CW10" smd circle
			(at -25.999948 28.710128 180)
			(size 0.450088 0.450088)
			(layers "F.Cu" "F.Mask" "F.Paste")
			(net "M_L_CPU1_SB_DQ<21>")
		)
		(pad "CW11" smd circle
			(at -25.059894 28.710128 180)
			(size 0.450088 0.450088)
			(layers "F.Cu" "F.Mask" "F.Paste")
			(net "PVDD11_S3_P1")
		)
		(pad "CW12" smd circle
			(at -24.120094 28.710128 180)
			(size 0.450088 0.450088)
			(layers "F.Cu" "F.Mask" "F.Paste")
			(net "M_H_CPU1_SB_DQ<22>")
		)
		(pad "CW13" smd circle
			(at -23.18004 28.710128 180)
			(size 0.450088 0.450088)
			(layers "F.Cu" "F.Mask" "F.Paste")
			(net "GND")
		)
		(pad "CW14" smd circle
			(at -22.239986 28.710128 180)
			(size 0.450088 0.450088)
			(layers "F.Cu" "F.Mask" "F.Paste")
			(net "M_H_CPU1_SB_DQ<21>")
		)
		(pad "CW15" smd circle
			(at -21.299932 28.710128 180)
			(size 0.450088 0.450088)
			(layers "F.Cu" "F.Mask" "F.Paste")
			(net "GND")
		)
		(pad "CW16" smd circle
			(at -20.359878 28.710128 180)
			(size 0.450088 0.450088)
			(layers "F.Cu" "F.Mask" "F.Paste")
			(net "M_J_CPU1_SB_DQ<22>")
		)
		(pad "CW17" smd circle
			(at -19.420078 28.710128 180)
			(size 0.450088 0.450088)
			(layers "F.Cu" "F.Mask" "F.Paste")
			(net "M_J_CPU1_SB_DQ<21>")
		)
		(pad "CW18" smd circle
			(at -18.480024 28.710128 180)
			(size 0.450088 0.450088)
			(layers "F.Cu" "F.Mask" "F.Paste")
			(net "PVDD11_S3_P1")
		)
		(pad "CW19" smd circle
			(at -17.53997 28.710128 180)
			(size 0.450088 0.450088)
			(layers "F.Cu" "F.Mask" "F.Paste")
			(net "M_I_CPU1_SB_DQ<22>")
		)
		(pad "CW20" smd circle
			(at -16.599916 28.710128 180)
			(size 0.450088 0.450088)
			(layers "F.Cu" "F.Mask" "F.Paste")
			(net "GND")
		)
		(pad "CW21" smd circle
			(at -15.660116 28.710128 180)
			(size 0.450088 0.450088)
			(layers "F.Cu" "F.Mask" "F.Paste")
			(net "M_I_CPU1_SB_DQ<21>")
		)
		(pad "CW22" smd circle
			(at -14.720062 28.710128 180)
			(size 0.450088 0.450088)
			(layers "F.Cu" "F.Mask" "F.Paste")
			(net "GND")
		)
		(pad "CW23" smd circle
			(at -13.780008 28.710128 180)
			(size 0.450088 0.450088)
			(layers "F.Cu" "F.Mask" "F.Paste")
			(net "P5E_CPU1_P3_RX_DP<12>")
		)
		(pad "CW24" smd circle
			(at -12.839954 28.710128 180)
			(size 0.450088 0.450088)
			(layers "F.Cu" "F.Mask" "F.Paste")
			(net "P5E_CPU1_P3_RX_DN<12>")
		)
		(pad "CW25" smd circle
			(at -11.8999 28.710128 180)
			(size 0.450088 0.450088)
			(layers "F.Cu" "F.Mask" "F.Paste")
			(net "GND")
		)
		(pad "CW26" smd circle
			(at -10.9601 28.710128 180)
			(size 0.450088 0.450088)
			(layers "F.Cu" "F.Mask" "F.Paste")
			(net "P5E_CPU1_P3_RX_DP<9>")
		)
		(pad "CW27" smd circle
			(at -10.020046 28.710128 180)
			(size 0.450088 0.450088)
			(layers "F.Cu" "F.Mask" "F.Paste")
			(net "P5E_CPU1_P3_RX_DN<9>")
		)
		(pad "CW28" smd circle
			(at -9.079992 28.710128 180)
			(size 0.450088 0.450088)
			(layers "F.Cu" "F.Mask" "F.Paste")
			(net "GND")
		)
		(pad "CW29" smd circle
			(at -8.139938 28.710128 180)
			(size 0.450088 0.450088)
			(layers "F.Cu" "F.Mask" "F.Paste")
			(net "P5E_CPU1_P3_RX_DP<6>")
		)
		(pad "CW30" smd circle
			(at -7.199884 28.710128 180)
			(size 0.450088 0.450088)
			(layers "F.Cu" "F.Mask" "F.Paste")
			(net "P5E_CPU1_P3_RX_DN<6>")
		)
		(pad "CW31" smd circle
			(at -6.260084 28.710128 180)
			(size 0.450088 0.450088)
			(layers "F.Cu" "F.Mask" "F.Paste")
			(net "GND")
		)
		(pad "CW32" smd circle
			(at -5.32003 28.710128 180)
			(size 0.450088 0.450088)
			(layers "F.Cu" "F.Mask" "F.Paste")
			(net "P5E_CPU1_P3_RX_DP<3>")
		)
		(pad "CW33" smd circle
			(at -4.379976 28.710128 180)
			(size 0.450088 0.450088)
			(layers "F.Cu" "F.Mask" "F.Paste")
			(net "P5E_CPU1_P3_RX_DN<3>")
		)
		(pad "CW34" smd circle
			(at -3.439922 28.710128 180)
			(size 0.450088 0.450088)
			(layers "F.Cu" "F.Mask" "F.Paste")
			(net "GND")
		)
		(pad "CW35" smd circle
			(at -2.500122 28.710128 180)
			(size 0.450088 0.450088)
			(layers "F.Cu" "F.Mask" "F.Paste")
			(net "GND")
		)
		(pad "CW36" smd circle
			(at -1.560068 28.710128 180)
			(size 0.450088 0.450088)
			(layers "F.Cu" "F.Mask" "F.Paste")
			(net "GND")
		)
		(pad "CW40" smd circle
			(at 1.260094 28.710128 180)
			(size 0.450088 0.450088)
			(layers "F.Cu" "F.Mask" "F.Paste")
			(net "GND")
		)
		(pad "CW41" smd circle
			(at 2.199894 28.710128 180)
			(size 0.450088 0.450088)
			(layers "F.Cu" "F.Mask" "F.Paste")
			(net "GND")
		)
		(pad "CW42" smd circle
			(at 3.139948 28.710128 180)
			(size 0.450088 0.450088)
			(layers "F.Cu" "F.Mask" "F.Paste")
			(net "GND")
		)
		(pad "CW43" smd circle
			(at 4.080002 28.710128 180)
			(size 0.450088 0.450088)
			(layers "F.Cu" "F.Mask" "F.Paste")
			(net "P5E_CPU1_P1_TX_DN<12>")
		)
		(pad "CW44" smd circle
			(at 5.020056 28.710128 180)
			(size 0.450088 0.450088)
			(layers "F.Cu" "F.Mask" "F.Paste")
			(net "P5E_CPU1_P1_TX_DP<12>")
		)
		(pad "CW45" smd circle
			(at 5.96011 28.710128 180)
			(size 0.450088 0.450088)
			(layers "F.Cu" "F.Mask" "F.Paste")
			(net "GND")
		)
		(pad "CW46" smd circle
			(at 6.89991 28.710128 180)
			(size 0.450088 0.450088)
			(layers "F.Cu" "F.Mask" "F.Paste")
			(net "P5E_CPU1_P1_TX_DN<9>")
		)
		(pad "CW47" smd circle
			(at 7.839964 28.710128 180)
			(size 0.450088 0.450088)
			(layers "F.Cu" "F.Mask" "F.Paste")
			(net "P5E_CPU1_P1_TX_DP<9>")
		)
		(pad "CW48" smd circle
			(at 8.780018 28.710128 180)
			(size 0.450088 0.450088)
			(layers "F.Cu" "F.Mask" "F.Paste")
			(net "GND")
		)
		(pad "CW49" smd circle
			(at 9.720072 28.710128 180)
			(size 0.450088 0.450088)
			(layers "F.Cu" "F.Mask" "F.Paste")
			(net "P5E_CPU1_P1_TX_DN<6>")
		)
		(pad "CW50" smd circle
			(at 10.659872 28.710128 180)
			(size 0.450088 0.450088)
			(layers "F.Cu" "F.Mask" "F.Paste")
			(net "P5E_CPU1_P1_TX_DP<6>")
		)
		(pad "CW51" smd circle
			(at 11.599926 28.710128 180)
			(size 0.450088 0.450088)
			(layers "F.Cu" "F.Mask" "F.Paste")
			(net "GND")
		)
		(pad "CW52" smd circle
			(at 12.53998 28.710128 180)
			(size 0.450088 0.450088)
			(layers "F.Cu" "F.Mask" "F.Paste")
			(net "P5E_CPU1_P1_TX_DN<3>")
		)
		(pad "CW53" smd circle
			(at 13.480034 28.710128 180)
			(size 0.450088 0.450088)
			(layers "F.Cu" "F.Mask" "F.Paste")
			(net "P5E_CPU1_P1_TX_DP<3>")
		)
		(pad "CW54" smd circle
			(at 14.420088 28.710128 180)
			(size 0.450088 0.450088)
			(layers "F.Cu" "F.Mask" "F.Paste")
			(net "GND")
		)
		(pad "CW55" smd circle
			(at 15.359888 28.710128 180)
			(size 0.450088 0.450088)
			(layers "F.Cu" "F.Mask" "F.Paste")
			(net "M_C_CPU1_SB_DQ<21>")
		)
		(pad "CW56" smd circle
			(at 16.299942 28.710128 180)
			(size 0.450088 0.450088)
			(layers "F.Cu" "F.Mask" "F.Paste")
			(net "GND")
		)
		(pad "CW57" smd circle
			(at 17.239996 28.710128 180)
			(size 0.450088 0.450088)
			(layers "F.Cu" "F.Mask" "F.Paste")
			(net "M_C_CPU1_SB_DQ<22>")
		)
		(pad "CW58" smd circle
			(at 18.18005 28.710128 180)
			(size 0.450088 0.450088)
			(layers "F.Cu" "F.Mask" "F.Paste")
			(net "PVDDIO_P1")
		)
		(pad "CW59" smd circle
			(at 19.120104 28.710128 180)
			(size 0.450088 0.450088)
			(layers "F.Cu" "F.Mask" "F.Paste")
			(net "M_D_CPU1_SB_DQ<21>")
		)
		(pad "CW60" smd circle
			(at 20.059904 28.710128 180)
			(size 0.450088 0.450088)
			(layers "F.Cu" "F.Mask" "F.Paste")
			(net "M_D_CPU1_SB_DQ<22>")
		)
		(pad "CW61" smd circle
			(at 20.999958 28.710128 180)
			(size 0.450088 0.450088)
			(layers "F.Cu" "F.Mask" "F.Paste")
			(net "GND")
		)
		(pad "CW62" smd circle
			(at 21.940012 28.710128 180)
			(size 0.450088 0.450088)
			(layers "F.Cu" "F.Mask" "F.Paste")
			(net "M_B_CPU1_SB_DQ<21>")
		)
		(pad "CW63" smd circle
			(at 22.880066 28.710128 180)
			(size 0.450088 0.450088)
			(layers "F.Cu" "F.Mask" "F.Paste")
			(net "GND")
		)
		(pad "CW64" smd circle
			(at 23.82012 28.710128 180)
			(size 0.450088 0.450088)
			(layers "F.Cu" "F.Mask" "F.Paste")
			(net "M_B_CPU1_SB_DQ<22>")
		)
		(pad "CW65" smd circle
			(at 24.75992 28.710128 180)
			(size 0.450088 0.450088)
			(layers "F.Cu" "F.Mask" "F.Paste")
			(net "PVDDIO_P1")
		)
		(pad "CW66" smd circle
			(at 25.699974 28.710128 180)
			(size 0.450088 0.450088)
			(layers "F.Cu" "F.Mask" "F.Paste")
			(net "M_F_CPU1_SB_DQ<21>")
		)
		(pad "CW67" smd circle
			(at 26.640028 28.710128 180)
			(size 0.450088 0.450088)
			(layers "F.Cu" "F.Mask" "F.Paste")
			(net "M_F_CPU1_SB_DQ<22>")
		)
		(pad "CW68" smd circle
			(at 27.580082 28.710128 180)
			(size 0.450088 0.450088)
			(layers "F.Cu" "F.Mask" "F.Paste")
			(net "GND")
		)
		(pad "CW69" smd circle
			(at 28.519882 28.710128 180)
			(size 0.450088 0.450088)
			(layers "F.Cu" "F.Mask" "F.Paste")
			(net "M_E_CPU1_SB_DQ<21>")
		)
		(pad "CW70" smd circle
			(at 29.459936 28.710128 180)
			(size 0.450088 0.450088)
			(layers "F.Cu" "F.Mask" "F.Paste")
			(net "GND")
		)
		(pad "CW71" smd circle
			(at 30.39999 28.710128 180)
			(size 0.450088 0.450088)
			(layers "F.Cu" "F.Mask" "F.Paste")
			(net "M_E_CPU1_SB_DQ<22>")
		)
		(pad "CW72" smd circle
			(at 31.340044 28.710128 180)
			(size 0.450088 0.450088)
			(layers "F.Cu" "F.Mask" "F.Paste")
			(net "PVDDIO_P1")
		)
		(pad "CW73" smd circle
			(at 32.280098 28.710128 180)
			(size 0.450088 0.450088)
			(layers "F.Cu" "F.Mask" "F.Paste")
			(net "M_A_CPU1_SB_DQ<21>")
		)
		(pad "CW74" smd circle
			(at 33.219898 28.710128 180)
			(size 0.450088 0.450088)
			(layers "F.Cu" "F.Mask" "F.Paste")
			(net "M_A_CPU1_SB_DQ<22>")
		)
		(pad "CW75" smd circle
			(at 34.159952 28.710128 180)
			(size 0.450088 0.450088)
			(layers "F.Cu" "F.Mask" "F.Paste")
			(net "GND")
		)
		(pad "CY2" smd circle
			(at -33.990026 29.51988 180)
			(size 0.450088 0.450088)
			(layers "F.Cu" "F.Mask" "F.Paste")
			(net "M_G_CPU1_SB_DQ<24>")
		)
		(pad "CY3" smd circle
			(at -33.049972 29.51988 180)
			(size 0.450088 0.450088)
			(layers "F.Cu" "F.Mask" "F.Paste")
			(net "GND")
		)
		(pad "CY4" smd circle
			(at -32.109918 29.51988 180)
			(size 0.450088 0.450088)
			(layers "F.Cu" "F.Mask" "F.Paste")
			(net "M_G_CPU1_SB_DQ<23>")
		)
		(pad "CY5" smd circle
			(at -31.170118 29.51988 180)
			(size 0.450088 0.450088)
			(layers "F.Cu" "F.Mask" "F.Paste")
			(net "GND")
		)
		(pad "CY6" smd circle
			(at -30.230064 29.51988 180)
			(size 0.450088 0.450088)
			(layers "F.Cu" "F.Mask" "F.Paste")
			(net "M_K_CPU1_SB_DQ<24>")
		)
		(pad "CY7" smd circle
			(at -29.29001 29.51988 180)
			(size 0.450088 0.450088)
			(layers "F.Cu" "F.Mask" "F.Paste")
			(net "M_K_CPU1_SB_DQ<23>")
		)
		(pad "CY8" smd circle
			(at -28.349956 29.51988 180)
			(size 0.450088 0.450088)
			(layers "F.Cu" "F.Mask" "F.Paste")
			(net "GND")
		)
		(pad "CY9" smd circle
			(at -27.409902 29.51988 180)
			(size 0.450088 0.450088)
			(layers "F.Cu" "F.Mask" "F.Paste")
			(net "M_L_CPU1_SB_DQ<24>")
		)
		(pad "CY10" smd circle
			(at -26.470102 29.51988 180)
			(size 0.450088 0.450088)
			(layers "F.Cu" "F.Mask" "F.Paste")
			(net "GND")
		)
		(pad "CY11" smd circle
			(at -25.530048 29.51988 180)
			(size 0.450088 0.450088)
			(layers "F.Cu" "F.Mask" "F.Paste")
			(net "M_L_CPU1_SB_DQ<23>")
		)
		(pad "CY12" smd circle
			(at -24.589994 29.51988 180)
			(size 0.450088 0.450088)
			(layers "F.Cu" "F.Mask" "F.Paste")
			(net "GND")
		)
		(pad "CY13" smd circle
			(at -23.64994 29.51988 180)
			(size 0.450088 0.450088)
			(layers "F.Cu" "F.Mask" "F.Paste")
			(net "M_H_CPU1_SB_DQ<24>")
		)
		(pad "CY14" smd circle
			(at -22.709886 29.51988 180)
			(size 0.450088 0.450088)
			(layers "F.Cu" "F.Mask" "F.Paste")
			(net "M_H_CPU1_SB_DQ<23>")
		)
		(pad "CY15" smd circle
			(at -21.770086 29.51988 180)
			(size 0.450088 0.450088)
			(layers "F.Cu" "F.Mask" "F.Paste")
			(net "GND")
		)
		(pad "CY16" smd circle
			(at -20.830032 29.51988 180)
			(size 0.450088 0.450088)
			(layers "F.Cu" "F.Mask" "F.Paste")
			(net "M_J_CPU1_SB_DQ<24>")
		)
		(pad "CY17" smd circle
			(at -19.889978 29.51988 180)
			(size 0.450088 0.450088)
			(layers "F.Cu" "F.Mask" "F.Paste")
			(net "GND")
		)
		(pad "CY18" smd circle
			(at -18.949924 29.51988 180)
			(size 0.450088 0.450088)
			(layers "F.Cu" "F.Mask" "F.Paste")
			(net "M_J_CPU1_SB_DQ<23>")
		)
		(pad "CY19" smd circle
			(at -18.010124 29.51988 180)
			(size 0.450088 0.450088)
			(layers "F.Cu" "F.Mask" "F.Paste")
			(net "GND")
		)
		(pad "CY20" smd circle
			(at -17.07007 29.51988 180)
			(size 0.450088 0.450088)
			(layers "F.Cu" "F.Mask" "F.Paste")
			(net "M_I_CPU1_SB_DQ<24>")
		)
		(pad "CY21" smd circle
			(at -16.130016 29.51988 180)
			(size 0.450088 0.450088)
			(layers "F.Cu" "F.Mask" "F.Paste")
			(net "M_I_CPU1_SB_DQ<23>")
		)
		(pad "CY22" smd circle
			(at -15.189962 29.51988 180)
			(size 0.450088 0.450088)
			(layers "F.Cu" "F.Mask" "F.Paste")
			(net "PVDD11_S3_P1")
		)
		(pad "CY23" smd circle
			(at -14.249908 29.51988 180)
			(size 0.450088 0.450088)
			(layers "F.Cu" "F.Mask" "F.Paste")
			(net "GND")
		)
		(pad "CY24" smd circle
			(at -13.310108 29.51988 180)
			(size 0.450088 0.450088)
			(layers "F.Cu" "F.Mask" "F.Paste")
			(net "GND")
		)
		(pad "CY25" smd circle
			(at -12.370054 29.51988 180)
			(size 0.450088 0.450088)
			(layers "F.Cu" "F.Mask" "F.Paste")
			(net "GND")
		)
		(pad "CY26" smd circle
			(at -11.43 29.51988 180)
			(size 0.450088 0.450088)
			(layers "F.Cu" "F.Mask" "F.Paste")
			(net "GND")
		)
		(pad "CY27" smd circle
			(at -10.489946 29.51988 180)
			(size 0.450088 0.450088)
			(layers "F.Cu" "F.Mask" "F.Paste")
			(net "GND")
		)
		(pad "CY28" smd circle
			(at -9.549892 29.51988 180)
			(size 0.450088 0.450088)
			(layers "F.Cu" "F.Mask" "F.Paste")
			(net "GND")
		)
		(pad "CY29" smd circle
			(at -8.610092 29.51988 180)
			(size 0.450088 0.450088)
			(layers "F.Cu" "F.Mask" "F.Paste")
			(net "GND")
		)
		(pad "CY30" smd circle
			(at -7.670038 29.51988 180)
			(size 0.450088 0.450088)
			(layers "F.Cu" "F.Mask" "F.Paste")
			(net "GND")
		)
		(pad "CY31" smd circle
			(at -6.729984 29.51988 180)
			(size 0.450088 0.450088)
			(layers "F.Cu" "F.Mask" "F.Paste")
			(net "GND")
		)
		(pad "CY32" smd circle
			(at -5.78993 29.51988 180)
			(size 0.450088 0.450088)
			(layers "F.Cu" "F.Mask" "F.Paste")
			(net "GND")
		)
		(pad "CY33" smd circle
			(at -4.849876 29.51988 180)
			(size 0.450088 0.450088)
			(layers "F.Cu" "F.Mask" "F.Paste")
			(net "GND")
		)
		(pad "CY34" smd circle
			(at -3.910076 29.51988 180)
			(size 0.450088 0.450088)
			(layers "F.Cu" "F.Mask" "F.Paste")
			(net "GND")
		)
		(pad "CY35" smd circle
			(at -2.970022 29.51988 180)
			(size 0.450088 0.450088)
			(layers "F.Cu" "F.Mask" "F.Paste")
			(net "P5E_CPU1_P3_RX_DP<1>")
		)
		(pad "CY36" smd circle
			(at -2.029968 29.51988 180)
			(size 0.450088 0.450088)
			(layers "F.Cu" "F.Mask" "F.Paste")
			(net "P5E_CPU1_P3_RX_DN<1>")
		)
		(pad "CY37" smd circle
			(at -1.089914 29.51988 180)
			(size 0.450088 0.450088)
			(layers "F.Cu" "F.Mask" "F.Paste")
			(net "GND")
		)
		(pad "CY39" smd circle
			(at 0.78994 29.51988 180)
			(size 0.450088 0.450088)
			(layers "F.Cu" "F.Mask" "F.Paste")
			(net "GND")
		)
		(pad "CY40" smd circle
			(at 1.729994 29.51988 180)
			(size 0.450088 0.450088)
			(layers "F.Cu" "F.Mask" "F.Paste")
			(net "P5E_CPU1_P1_TX_DN<14>")
		)
		(pad "CY41" smd circle
			(at 2.670048 29.51988 180)
			(size 0.450088 0.450088)
			(layers "F.Cu" "F.Mask" "F.Paste")
			(net "P5E_CPU1_P1_TX_DP<14>")
		)
		(pad "CY42" smd circle
			(at 3.610102 29.51988 180)
			(size 0.450088 0.450088)
			(layers "F.Cu" "F.Mask" "F.Paste")
			(net "GND")
		)
		(pad "CY43" smd circle
			(at 4.549902 29.51988 180)
			(size 0.450088 0.450088)
			(layers "F.Cu" "F.Mask" "F.Paste")
			(net "GND")
		)
		(pad "CY44" smd circle
			(at 5.489956 29.51988 180)
			(size 0.450088 0.450088)
			(layers "F.Cu" "F.Mask" "F.Paste")
			(net "GND")
		)
		(pad "CY45" smd circle
			(at 6.43001 29.51988 180)
			(size 0.450088 0.450088)
			(layers "F.Cu" "F.Mask" "F.Paste")
			(net "GND")
		)
		(pad "CY46" smd circle
			(at 7.370064 29.51988 180)
			(size 0.450088 0.450088)
			(layers "F.Cu" "F.Mask" "F.Paste")
			(net "GND")
		)
		(pad "CY47" smd circle
			(at 8.310118 29.51988 180)
			(size 0.450088 0.450088)
			(layers "F.Cu" "F.Mask" "F.Paste")
			(net "GND")
		)
		(pad "CY48" smd circle
			(at 9.249918 29.51988 180)
			(size 0.450088 0.450088)
			(layers "F.Cu" "F.Mask" "F.Paste")
			(net "GND")
		)
		(pad "CY49" smd circle
			(at 10.189972 29.51988 180)
			(size 0.450088 0.450088)
			(layers "F.Cu" "F.Mask" "F.Paste")
			(net "GND")
		)
		(pad "CY50" smd circle
			(at 11.130026 29.51988 180)
			(size 0.450088 0.450088)
			(layers "F.Cu" "F.Mask" "F.Paste")
			(net "GND")
		)
	)
)
